# SCM (Grand Teton) — schematic netlist excerpt (pin names and nets, part order shuffled) for the footprints in the layout excerpt that follows; sources: Cadence DE-HDL packaged netlist, KiCad conversion of 12092022_DA0F0TMDCD0_F0T_Management_Board_D_brd_V3_OCP.brd

C166  Q_CAP  1UF 25V 10% X6S  pkg C0402  page 41 : A = VCCIO0 ; B = GND
C220  Q_CAP  0.1UF 25V 10% X7R  pkg 0402  page 41 : A = VCCIO4 ; B = GND
C266  Q_CAP  0.1UF 25V 10% X7R  pkg 0402  page 41 : A = PVCCA_AUX_PLD ; B = GND

(kicad_pcb
	(version 20260206)
	(generator "pcbnew")
	(generator_version "10.0")
	(general
		(thickness 1.6)
		(legacy_teardrops no)
	)
	(paper "A4")
	(title_block
		(title "12092022_DA0F0TMDCD0_F0T_Management_Board_D_brd_V3_OCP.brd")
		(comment 1 "Grand Teton / footprints 944-946 of 1440")
	)
	(layers
		(0 "F.Cu" signal "TOP")
		(4 "In1.Cu" signal "GND")
		(6 "In2.Cu" signal "IN1")
		(8 "In3.Cu" signal "GND1")
		(10 "In4.Cu" signal "IN2")
		(12 "In5.Cu" signal "VCC")
		(14 "In6.Cu" signal "VCC1")
		(16 "In7.Cu" signal "IN3")
		(18 "In8.Cu" signal "GND2")
		(20 "In9.Cu" signal "IN4")
		(22 "In10.Cu" signal "GND3")
		(2 "B.Cu" signal "BOTTOM")
		(9 "F.Adhes" user "F.Adhesive")
		(11 "B.Adhes" user "B.Adhesive")
		(13 "F.Paste" user "Package Geometry/Pastemask Top")
		(15 "B.Paste" user "Package Geometry/Pastemask Bottom")
		(5 "F.SilkS" user "Ref Des/Silkscreen Top")
		(7 "B.SilkS" user "Ref Des/Silkscreen Bottom")
		(1 "F.Mask" user "Board Geometry/Soldermask Top")
		(3 "B.Mask" user "Board Geometry/Soldermask Bottom")
		(17 "Dwgs.User" user "User.Drawings")
		(19 "Cmts.User" user "User.Comments")
		(21 "Eco1.User" user "User.Eco1")
		(23 "Eco2.User" user "User.Eco2")
		(25 "Edge.Cuts" user "Board Geometry/Outline")
		(27 "Margin" user)
		(31 "F.CrtYd" user "Package Geometry/Place Bound Top")
		(29 "B.CrtYd" user "Package Geometry/Place Bound Bottom")
		(35 "F.Fab" user "Ref Des/Assembly Top")
		(33 "B.Fab" user "Ref Des/Assembly Bottom")
	)
	(footprint ""
		(layer "B.Cu")
		(at 22.65934 -91.187016 90)
		(property "Reference" "C166"
			(at 0 0 90)
			(layer "B.SilkS")
			(hide yes)
			(effects
				(font
					(size 1.27 1.27)
				)
				(justify mirror)
			)
		)
		(property "Value" ""
			(at 0 0 90)
			(layer "B.Fab")
			(effects
				(font
					(size 1.27 1.27)
				)
				(justify mirror)
			)
		)
		(duplicate_pad_numbers_are_jumpers no)
		(fp_line
			(start 0.69215 -0.2921)
			(end -0.69215 -0.2921)
			(stroke
				(width 0.1524)
				(type default)
			)
			(layer "B.SilkS")
		)
		(fp_line
			(start -0.69215 -0.2921)
			(end -0.69215 0.2921)
			(stroke
				(width 0.1524)
				(type default)
			)
			(layer "B.SilkS")
		)
		(fp_line
			(start 0.69215 0.2921)
			(end 0.69215 -0.2921)
			(stroke
				(width 0.1524)
				(type default)
			)
			(layer "B.SilkS")
		)
		(fp_line
			(start -0.69215 0.2921)
			(end 0.69215 0.2921)
			(stroke
				(width 0.1524)
				(type default)
			)
			(layer "B.SilkS")
		)
		(fp_line
			(start 0.51435 -0.2794)
			(end -0.51435 -0.2794)
			(stroke
				(width 0.1)
				(type default)
			)
			(layer "B.Fab")
		)
		(fp_line
			(start -0.51435 -0.2794)
			(end -0.51435 0.2794)
			(stroke
				(width 0.1)
				(type default)
			)
			(layer "B.Fab")
		)
		(fp_line
			(start 0.51435 0.2794)
			(end 0.51435 -0.2794)
			(stroke
				(width 0.1)
				(type default)
			)
			(layer "B.Fab")
		)
		(fp_line
			(start -0.51435 0.2794)
			(end 0.51435 0.2794)
			(stroke
				(width 0.1)
				(type default)
			)
			(layer "B.Fab")
		)
		(pad "1" smd circle
			(at 0.40005 0 270)
			(size 0 0)
			(layers "B.Cu" "B.Mask" "B.Paste")
			(net "VCCIO0")
		)
		(pad "2" smd circle
			(at -0.40005 0 270)
			(size 0 0)
			(layers "B.Cu" "B.Mask" "B.Paste")
			(net "GND")
		)
		(zone
			(layer "B.Cu")
			(hatch none 0.5)
			(connect_pads
				(clearance 0)
			)
			(min_thickness 0.25)
			(keepout
				(tracks not_allowed)
				(vias allowed)
				(pads allowed)
				(copperpour not_allowed)
				(footprints allowed)
			)
			(placement
				(enabled no)
				(sheetname "")
			)
			(fill
				(thermal_gap 0.5)
				(thermal_bridge_width 0.5)
				(island_removal_mode 0)
			)
			(polygon
				(pts
					(xy 22.74697 -91.377516) (xy 22.805136 -91.286076) (xy 22.805136 -91.086686) (xy 22.74697 -90.996516)
					(xy 22.57171 -90.996516) (xy 22.51329 -91.086686) (xy 22.51329 -91.286076) (xy 22.571456 -91.377516)
				)
			)
		)
	)
	(footprint ""
		(layer "B.Cu")
		(at 27.682444 -99.448112 45)
		(property "Reference" "C266"
			(at 0 0 45)
			(layer "B.SilkS")
			(hide yes)
			(effects
				(font
					(size 1.27 1.27)
				)
				(justify mirror)
			)
		)
		(property "Value" ""
			(at 0 0 45)
			(layer "B.Fab")
			(effects
				(font
					(size 1.27 1.27)
				)
				(justify mirror)
			)
		)
		(duplicate_pad_numbers_are_jumpers no)
		(fp_line
			(start -0.787389 -0.406267)
			(end -0.787389 0.406267)
			(stroke
				(width 0.1524)
				(type default)
			)
			(layer "B.SilkS")
		)
		(fp_line
			(start -0.787389 0.406267)
			(end 0.787389 0.406267)
			(stroke
				(width 0.1524)
				(type default)
			)
			(layer "B.SilkS")
		)
		(fp_line
			(start 0.787389 -0.406267)
			(end -0.787389 -0.406267)
			(stroke
				(width 0.1524)
				(type default)
			)
			(layer "B.SilkS")
		)
		(fp_line
			(start 0.787389 0.406267)
			(end 0.787389 -0.406267)
			(stroke
				(width 0.1524)
				(type default)
			)
			(layer "B.SilkS")
		)
		(fp_line
			(start -0.679446 -0.30479)
			(end -0.679446 0.30479)
			(stroke
				(width 0.1)
				(type default)
			)
			(layer "B.Fab")
		)
		(fp_line
			(start -0.120515 -0.30479)
			(end -0.679446 -0.30479)
			(stroke
				(width 0.1)
				(type default)
			)
			(layer "B.Fab")
		)
		(fp_line
			(start -0.120695 -0.279466)
			(end -0.120515 -0.30479)
			(stroke
				(width 0.1)
				(type default)
			)
			(layer "B.Fab")
		)
		(fp_line
			(start -0.679446 0.30479)
			(end -0.120515 0.30479)
			(stroke
				(width 0.1)
				(type default)
			)
			(layer "B.Fab")
		)
		(fp_line
			(start 0.120695 -0.304969)
			(end 0.120695 -0.279466)
			(stroke
				(width 0.1)
				(type default)
			)
			(layer "B.Fab")
		)
		(fp_line
			(start 0.120695 -0.279466)
			(end -0.120695 -0.279466)
			(stroke
				(width 0.1)
				(type default)
			)
			(layer "B.Fab")
		)
		(fp_line
			(start -0.120335 0.279466)
			(end 0.120695 0.279466)
			(stroke
				(width 0.1)
				(type default)
			)
			(layer "B.Fab")
		)
		(fp_line
			(start -0.120515 0.30479)
			(end -0.120335 0.279466)
			(stroke
				(width 0.1)
				(type default)
			)
			(layer "B.Fab")
		)
		(fp_line
			(start 0.679446 -0.305149)
			(end 0.120695 -0.304969)
			(stroke
				(width 0.1)
				(type default)
			)
			(layer "B.Fab")
		)
		(fp_line
			(start 0.120695 0.279466)
			(end 0.120515 0.30479)
			(stroke
				(width 0.1)
				(type default)
			)
			(layer "B.Fab")
		)
		(fp_line
			(start 0.120515 0.30479)
			(end 0.679446 0.30479)
			(stroke
				(width 0.1)
				(type default)
			)
			(layer "B.Fab")
		)
		(fp_line
			(start 0.679446 0.30479)
			(end 0.679446 -0.305149)
			(stroke
				(width 0.1)
				(type default)
			)
			(layer "B.Fab")
		)
		(pad "1" smd circle
			(at 0.40005 0 225)
			(size 0 0)
			(layers "B.Cu" "B.Mask" "B.Paste")
			(net "PVCCA_AUX_PLD")
		)
		(pad "2" smd circle
			(at -0.40005 0 225)
			(size 0 0)
			(layers "B.Cu" "B.Mask" "B.Paste")
			(net "GND")
		)
	)
	(footprint ""
		(layer "B.Cu")
		(at 24.384 -93.345 180)
		(property "Reference" "C220"
			(at 0 0 0)
			(layer "B.SilkS")
			(hide yes)
			(effects
				(font
					(size 1.27 1.27)
				)
				(justify mirror)
			)
		)
		(property "Value" ""
			(at 0 0 0)
			(layer "B.Fab")
			(effects
				(font
					(size 1.27 1.27)
				)
				(justify mirror)
			)
		)
		(duplicate_pad_numbers_are_jumpers no)
		(fp_line
			(start 0.69215 0.2921)
			(end 0.69215 -0.2921)
			(stroke
				(width 0.1524)
				(type default)
			)
			(layer "B.SilkS")
		)
		(fp_line
			(start 0.69215 -0.2921)
			(end -0.69215 -0.2921)
			(stroke
				(width 0.1524)
				(type default)
			)
			(layer "B.SilkS")
		)
		(fp_line
			(start -0.69215 0.2921)
			(end 0.69215 0.2921)
			(stroke
				(width 0.1524)
				(type default)
			)
			(layer "B.SilkS")
		)
		(fp_line
			(start -0.69215 -0.2921)
			(end -0.69215 0.2921)
			(stroke
				(width 0.1524)
				(type default)
			)
			(layer "B.SilkS")
		)
		(fp_line
			(start 0.51435 0.2794)
			(end 0.51435 -0.2794)
			(stroke
				(width 0.1)
				(type default)
			)
			(layer "B.Fab")
		)
		(fp_line
			(start 0.51435 -0.2794)
			(end -0.51435 -0.2794)
			(stroke
				(width 0.1)
				(type default)
			)
			(layer "B.Fab")
		)
		(fp_line
			(start -0.51435 0.2794)
			(end 0.51435 0.2794)
			(stroke
				(width 0.1)
				(type default)
			)
			(layer "B.Fab")
		)
		(fp_line
			(start -0.51435 -0.2794)
			(end -0.51435 0.2794)
			(stroke
				(width 0.1)
				(type default)
			)
			(layer "B.Fab")
		)
		(pad "1" smd circle
			(at 0.40005 0)
			(size 0 0)
			(layers "B.Cu" "B.Mask" "B.Paste")
			(net "VCCIO4")
		)
		(pad "2" smd circle
			(at -0.40005 0)
			(size 0 0)
			(layers "B.Cu" "B.Mask" "B.Paste")
			(net "GND")
		)
		(zone
			(layer "B.Cu")
			(hatch none 0.5)
			(connect_pads
				(clearance 0)
			)
			(min_thickness 0.25)
			(keepout
				(tracks not_allowed)
				(vias allowed)
				(pads allowed)
				(copperpour not_allowed)
				(footprints allowed)
			)
			(placement
				(enabled no)
				(sheetname "")
			)
			(fill
				(thermal_gap 0.5)
				(thermal_bridge_width 0.5)
				(island_removal_mode 0)
			)
			(polygon
				(pts
					(xy 24.1935 -93.43263) (xy 24.28494 -93.490796) (xy 24.48433 -93.490796) (xy 24.5745 -93.43263)
					(xy 24.5745 -93.25737) (xy 24.48433 -93.19895) (xy 24.28494 -93.19895) (xy 24.1935 -93.257116)
				)
			)
		)
	)
)
